(kicad_pcb
	(version 20260206)
	(generator "pcbnew")
	(generator_version "10.0")
	(general
		(thickness 1.6)
		(legacy_teardrops no)
	)
	(paper "A4")
	(title_block
		(title "panther-plus-userver — 13130-1b_20150205.brd")
		(comment 1 "Honey Badger (Wiwynn) / footprint 282 of 1509 (U13), pads 938-1055 of 1283")
	)
	(layers
		(0 "F.Cu" signal "TOP")
		(4 "In1.Cu" signal "L2")
		(6 "In2.Cu" signal "L3")
		(8 "In3.Cu" signal "L4")
		(10 "In4.Cu" signal "L5")
		(12 "In5.Cu" signal "L6")
		(14 "In6.Cu" signal "L7")
		(16 "In7.Cu" signal "L8")
		(18 "In8.Cu" signal "L9")
		(20 "In9.Cu" signal "L10")
		(22 "In10.Cu" signal "L11")
		(2 "B.Cu" signal "BOTTOM")
		(9 "F.Adhes" user "F.Adhesive")
		(11 "B.Adhes" user "B.Adhesive")
		(13 "F.Paste" user "Package Geometry/Pastemask Top")
		(15 "B.Paste" user "Package Geometry/Pastemask Bottom")
		(5 "F.SilkS" user "Ref Des/Silkscreen Top")
		(7 "B.SilkS" user "Ref Des/Silkscreen Bottom")
		(1 "F.Mask" user "Board Geometry/Soldermask Top")
		(3 "B.Mask" user "Board Geometry/Soldermask Bottom")
		(17 "Dwgs.User" user "User.Drawings")
		(19 "Cmts.User" user "User.Comments")
		(21 "Eco1.User" user "User.Eco1")
		(23 "Eco2.User" user "User.Eco2")
		(25 "Edge.Cuts" user "Board Geometry/Outline")
		(27 "Margin" user)
		(31 "F.CrtYd" user "Package Geometry/Place Bound Top")
		(29 "B.CrtYd" user "Package Geometry/Place Bound Bottom")
		(35 "F.Fab" user "Ref Des/Assembly Top")
		(33 "B.Fab" user "Ref Des/Assembly Bottom")
	)
	(footprint ""
		(layer "F.Cu")
		(at 95.849948 -39.200074 180)
		(property "Reference" "U13"
			(at 0 0 180)
			(layer "F.SilkS")
			(hide yes)
			(effects
				(font
					(size 1.27 1.27)
				)
			)
		)
		(property "Value" "AVOTON-GP"
			(at -25.0317 -2.4892 180)
			(unlocked yes)
			(layer "F.Fab")
			(hide yes)
			(effects
				(font
					(size 1.016 1.016)
					(thickness 0.1524)
				)
			)
		)
		(property "Device Type" "BGA1283M3428-3H197"
			(at -25.0317 -4.0132 180)
			(unlocked yes)
			(layer "F.Fab")
			(hide yes)
			(effects
				(font
					(size 1.016 1.016)
					(thickness 0.1524)
				)
			)
		)
		(duplicate_pad_numbers_are_jumpers no)
		(pad "E46" smd circle
			(at 6.3119 -11.20394 180)
			(size 0.3048 0.3048)
			(layers "F.Cu" "F.Mask" "F.Paste")
			(net "GND")
		)
		(pad "E48" smd circle
			(at 7.0104 -11.20394 180)
			(size 0.3048 0.3048)
			(layers "F.Cu" "F.Mask" "F.Paste")
			(net "GND")
		)
		(pad "E49" smd circle
			(at 7.68858 -11.01344 180)
			(size 0.3048 0.3048)
			(layers "F.Cu" "F.Mask" "F.Paste")
			(net "GND")
		)
		(pad "E50" smd circle
			(at 8.39216 -11.06424 180)
			(size 0.3048 0.3048)
			(layers "F.Cu" "F.Mask" "F.Paste")
			(net "GND")
		)
		(pad "E52" smd circle
			(at 9.41324 -11.06424 180)
			(size 0.3048 0.3048)
			(layers "F.Cu" "F.Mask" "F.Paste")
			(net "GND")
		)
		(pad "E54" smd circle
			(at 10.11936 -11.07948 180)
			(size 0.3048 0.3048)
			(layers "F.Cu" "F.Mask" "F.Paste")
			(net "GND")
		)
		(pad "E55" smd circle
			(at 10.81532 -11.20394 180)
			(size 0.3048 0.3048)
			(layers "F.Cu" "F.Mask" "F.Paste")
			(net "GND")
		)
		(pad "E57" smd circle
			(at 11.51382 -11.20394 180)
			(size 0.3048 0.3048)
			(layers "F.Cu" "F.Mask" "F.Paste")
			(net "Net_1347")
		)
		(pad "E58" smd circle
			(at 12.192 -11.01344 180)
			(size 0.3048 0.3048)
			(layers "F.Cu" "F.Mask" "F.Paste")
			(net "Net_1355")
		)
		(pad "E59" smd circle
			(at 12.89558 -11.06424 180)
			(size 0.3048 0.3048)
			(layers "F.Cu" "F.Mask" "F.Paste")
			(net "GND")
		)
		(pad "E61" smd circle
			(at 13.91666 -11.06424 180)
			(size 0.3048 0.3048)
			(layers "F.Cu" "F.Mask" "F.Paste")
			(net "GND")
		)
		(pad "E62" smd circle
			(at 14.48562 -11.48588 180)
			(size 0.4064 0.4064)
			(layers "F.Cu" "F.Mask" "F.Paste")
			(net "Net_1352")
		)
		(pad "E64" smd circle
			(at 15.29842 -11.48588 180)
			(size 0.4064 0.4064)
			(layers "F.Cu" "F.Mask" "F.Paste")
			(net "GND")
		)
		(pad "E66" smd circle
			(at 16.11122 -11.48588 180)
			(size 0.4064 0.4064)
			(layers "F.Cu" "F.Mask" "F.Paste")
			(net "GND")
		)
		(pad "F1" smd circle
			(at -16.11122 -10.67308 180)
			(size 0.4064 0.4064)
			(layers "F.Cu" "F.Mask" "F.Paste")
			(net "GND")
		)
		(pad "F4" smd circle
			(at -14.89964 -10.69594 180)
			(size 0.3048 0.3048)
			(layers "F.Cu" "F.Mask" "F.Paste")
			(net "GND")
		)
		(pad "F5" smd circle
			(at -14.20368 -10.81278 180)
			(size 0.3048 0.3048)
			(layers "F.Cu" "F.Mask" "F.Paste")
			(net "GND")
		)
		(pad "F63" smd circle
			(at 14.89964 -10.90422 180)
			(size 0.3048 0.3048)
			(layers "F.Cu" "F.Mask" "F.Paste")
			(net "GND")
		)
		(pad "F66" smd circle
			(at 16.11122 -10.67308 180)
			(size 0.4064 0.4064)
			(layers "F.Cu" "F.Mask" "F.Paste")
			(net "GND")
		)
		(pad "G3" smd circle
			(at -15.29842 -10.1092 180)
			(size 0.3048 0.3048)
			(layers "F.Cu" "F.Mask" "F.Paste")
			(net "M_B_MA13")
		)
		(pad "G5" smd circle
			(at -14.08176 -10.11936 180)
			(size 0.3048 0.3048)
			(layers "F.Cu" "F.Mask" "F.Paste")
			(net "PV_VDDR")
		)
		(pad "G7" smd circle
			(at -13.34516 -10.16254 180)
			(size 0.3048 0.3048)
			(layers "F.Cu" "F.Mask" "F.Paste")
			(net "PV_VDDR")
		)
		(pad "G9" smd circle
			(at -12.38758 -10.34542 180)
			(size 0.3048 0.3048)
			(layers "F.Cu" "F.Mask" "F.Paste")
			(net "M_B_CK_DP1")
		)
		(pad "G10" smd circle
			(at -11.68654 -10.34542 180)
			(size 0.3048 0.3048)
			(layers "F.Cu" "F.Mask" "F.Paste")
			(net "M_B_CK_DN2")
		)
		(pad "G17" smd circle
			(at -8.41502 -10.34542 180)
			(size 0.3048 0.3048)
			(layers "F.Cu" "F.Mask" "F.Paste")
			(net "M_B_MA1")
		)
		(pad "G18" smd circle
			(at -7.71398 -10.34542 180)
			(size 0.3048 0.3048)
			(layers "F.Cu" "F.Mask" "F.Paste")
			(net "M_B_MA2")
		)
		(pad "G25" smd circle
			(at -4.44246 -10.34542 180)
			(size 0.3048 0.3048)
			(layers "F.Cu" "F.Mask" "F.Paste")
			(net "M_B_MA12")
		)
		(pad "G26" smd circle
			(at -3.74142 -10.34542 180)
			(size 0.3048 0.3048)
			(layers "F.Cu" "F.Mask" "F.Paste")
			(net "M_B_MA14")
		)
		(pad "G32" smd circle
			(at -0.4699 -10.34542 180)
			(size 0.3048 0.3048)
			(layers "F.Cu" "F.Mask" "F.Paste")
			(net "GND")
		)
		(pad "G34" smd circle
			(at 0.23114 -10.34542 180)
			(size 0.3048 0.3048)
			(layers "F.Cu" "F.Mask" "F.Paste")
			(net "GND")
		)
		(pad "G41" smd circle
			(at 3.50266 -10.34542 180)
			(size 0.3048 0.3048)
			(layers "F.Cu" "F.Mask" "F.Paste")
			(net "GND")
		)
		(pad "G42" smd circle
			(at 4.2037 -10.34542 180)
			(size 0.3048 0.3048)
			(layers "F.Cu" "F.Mask" "F.Paste")
			(net "Net_1359")
		)
		(pad "G48" smd circle
			(at 7.47522 -10.34542 180)
			(size 0.3048 0.3048)
			(layers "F.Cu" "F.Mask" "F.Paste")
			(net "GND")
		)
		(pad "G50" smd circle
			(at 8.17626 -10.34542 180)
			(size 0.3048 0.3048)
			(layers "F.Cu" "F.Mask" "F.Paste")
			(net "GBE_OBSP")
		)
		(pad "G56" smd circle
			(at 11.44778 -10.34542 180)
			(size 0.3048 0.3048)
			(layers "F.Cu" "F.Mask" "F.Paste")
			(net "GND")
		)
		(pad "G59" smd circle
			(at 12.58316 -10.34542 180)
			(size 0.3048 0.3048)
			(layers "F.Cu" "F.Mask" "F.Paste")
			(net "GND")
		)
		(pad "G62" smd circle
			(at 14.01318 -10.32256 180)
			(size 0.3048 0.3048)
			(layers "F.Cu" "F.Mask" "F.Paste")
			(net "Net_1356")
		)
		(pad "G64" smd circle
			(at 15.29842 -10.31748 180)
			(size 0.3048 0.3048)
			(layers "F.Cu" "F.Mask" "F.Paste")
			(net "Net_1353")
		)
		(pad "H1" smd circle
			(at -16.11122 -9.86028 180)
			(size 0.4064 0.4064)
			(layers "F.Cu" "F.Mask" "F.Paste")
			(net "GND")
		)
		(pad "H4" smd circle
			(at -14.75232 -9.58088 180)
			(size 0.3048 0.3048)
			(layers "F.Cu" "F.Mask" "F.Paste")
			(net "M_B_CAS#")
		)
		(pad "H9" smd circle
			(at -12.38758 -9.58342 180)
			(size 0.3048 0.3048)
			(layers "F.Cu" "F.Mask" "F.Paste")
			(net "M_B_CK_DN1")
		)
		(pad "H10" smd circle
			(at -11.68654 -9.58342 180)
			(size 0.3048 0.3048)
			(layers "F.Cu" "F.Mask" "F.Paste")
			(net "M_B_CK_DP2")
		)
		(pad "H13" smd circle
			(at -10.4013 -9.96442 180)
			(size 0.3048 0.3048)
			(layers "F.Cu" "F.Mask" "F.Paste")
			(net "PV_VDDR")
		)
		(pad "H14" smd circle
			(at -9.70026 -9.96442 180)
			(size 0.3048 0.3048)
			(layers "F.Cu" "F.Mask" "F.Paste")
			(net "PV_VDDR")
		)
		(pad "H17" smd circle
			(at -8.41502 -9.58342 180)
			(size 0.3048 0.3048)
			(layers "F.Cu" "F.Mask" "F.Paste")
			(net "M_B_MA0")
		)
		(pad "H18" smd circle
			(at -7.71398 -9.58342 180)
			(size 0.3048 0.3048)
			(layers "F.Cu" "F.Mask" "F.Paste")
			(net "M_B_BS1")
		)
		(pad "H21" smd circle
			(at -6.42874 -9.96442 180)
			(size 0.3048 0.3048)
			(layers "F.Cu" "F.Mask" "F.Paste")
			(net "M_B_MA8")
		)
		(pad "H22" smd circle
			(at -5.7277 -9.96442 180)
			(size 0.3048 0.3048)
			(layers "F.Cu" "F.Mask" "F.Paste")
			(net "M_B_MA5")
		)
		(pad "H25" smd circle
			(at -4.44246 -9.58342 180)
			(size 0.3048 0.3048)
			(layers "F.Cu" "F.Mask" "F.Paste")
			(net "M_B_BS2")
		)
		(pad "H26" smd circle
			(at -3.74142 -9.58342 180)
			(size 0.3048 0.3048)
			(layers "F.Cu" "F.Mask" "F.Paste")
			(net "M_B_MA15")
		)
		(pad "H29" smd circle
			(at -2.45618 -9.96442 180)
			(size 0.3048 0.3048)
			(layers "F.Cu" "F.Mask" "F.Paste")
			(net "M_B_DQ25")
		)
		(pad "H30" smd circle
			(at -1.75514 -9.96442 180)
			(size 0.3048 0.3048)
			(layers "F.Cu" "F.Mask" "F.Paste")
			(net "M_B_DQ24")
		)
		(pad "H32" smd circle
			(at -0.4699 -9.58342 180)
			(size 0.3048 0.3048)
			(layers "F.Cu" "F.Mask" "F.Paste")
			(net "M_B_DQ28")
		)
		(pad "H34" smd circle
			(at 0.23114 -9.58342 180)
			(size 0.3048 0.3048)
			(layers "F.Cu" "F.Mask" "F.Paste")
			(net "GND")
		)
		(pad "H37" smd circle
			(at 1.51638 -9.96442 180)
			(size 0.3048 0.3048)
			(layers "F.Cu" "F.Mask" "F.Paste")
			(net "GND")
		)
		(pad "H38" smd circle
			(at 2.21742 -9.96442 180)
			(size 0.3048 0.3048)
			(layers "F.Cu" "F.Mask" "F.Paste")
			(net "GND")
		)
		(pad "H41" smd circle
			(at 3.50266 -9.58342 180)
			(size 0.3048 0.3048)
			(layers "F.Cu" "F.Mask" "F.Paste")
			(net "GND")
		)
		(pad "H42" smd circle
			(at 4.2037 -9.58342 180)
			(size 0.3048 0.3048)
			(layers "F.Cu" "F.Mask" "F.Paste")
			(net "Net_1360")
		)
		(pad "H44" smd circle
			(at 5.48894 -9.96442 180)
			(size 0.3048 0.3048)
			(layers "F.Cu" "F.Mask" "F.Paste")
			(net "GND")
		)
		(pad "H46" smd circle
			(at 6.18998 -9.96442 180)
			(size 0.3048 0.3048)
			(layers "F.Cu" "F.Mask" "F.Paste")
			(net "GND")
		)
		(pad "H48" smd circle
			(at 7.47522 -9.58342 180)
			(size 0.3048 0.3048)
			(layers "F.Cu" "F.Mask" "F.Paste")
			(net "CPU_GBE_RX_DP0")
		)
		(pad "H50" smd circle
			(at 8.17626 -9.58342 180)
			(size 0.3048 0.3048)
			(layers "F.Cu" "F.Mask" "F.Paste")
			(net "GBE_OBSN")
		)
		(pad "H52" smd circle
			(at 9.4615 -9.96442 180)
			(size 0.3048 0.3048)
			(layers "F.Cu" "F.Mask" "F.Paste")
			(net "GND")
		)
		(pad "H54" smd circle
			(at 10.16254 -9.96442 180)
			(size 0.3048 0.3048)
			(layers "F.Cu" "F.Mask" "F.Paste")
			(net "GND")
		)
		(pad "H56" smd circle
			(at 11.44778 -9.58342 180)
			(size 0.3048 0.3048)
			(layers "F.Cu" "F.Mask" "F.Paste")
			(net "GND")
		)
		(pad "H58" smd circle
			(at 12.20216 -9.70026 180)
			(size 0.3048 0.3048)
			(layers "F.Cu" "F.Mask" "F.Paste")
			(net "GND")
		)
		(pad "H59" smd circle
			(at 12.96416 -9.70026 180)
			(size 0.3048 0.3048)
			(layers "F.Cu" "F.Mask" "F.Paste")
			(net "GND")
		)
		(pad "H62" smd circle
			(at 14.06398 -9.62152 180)
			(size 0.3048 0.3048)
			(layers "F.Cu" "F.Mask" "F.Paste")
			(net "SATA2_RX_DP0")
		)
		(pad "H63" smd circle
			(at 14.75232 -9.78916 180)
			(size 0.3048 0.3048)
			(layers "F.Cu" "F.Mask" "F.Paste")
			(net "SATA2_RX_DN0")
		)
		(pad "H66" smd circle
			(at 16.11122 -9.86028 180)
			(size 0.4064 0.4064)
			(layers "F.Cu" "F.Mask" "F.Paste")
			(net "GND")
		)
		(pad "J5" smd circle
			(at -14.06398 -9.41324 180)
			(size 0.3048 0.3048)
			(layers "F.Cu" "F.Mask" "F.Paste")
			(net "PV_VDDR")
		)
		(pad "J13" smd circle
			(at -10.4013 -9.20242 180)
			(size 0.3048 0.3048)
			(layers "F.Cu" "F.Mask" "F.Paste")
			(net "M_B_CK_DP3")
		)
		(pad "J14" smd circle
			(at -9.70026 -9.20242 180)
			(size 0.3048 0.3048)
			(layers "F.Cu" "F.Mask" "F.Paste")
			(net "CLK_100M_CPU_MPLL1_DP")
		)
		(pad "J21" smd circle
			(at -6.42874 -9.20242 180)
			(size 0.3048 0.3048)
			(layers "F.Cu" "F.Mask" "F.Paste")
			(net "M_B_MA6")
		)
		(pad "J22" smd circle
			(at -5.7277 -9.20242 180)
			(size 0.3048 0.3048)
			(layers "F.Cu" "F.Mask" "F.Paste")
			(net "M_B_MA7")
		)
		(pad "J29" smd circle
			(at -2.45618 -9.20242 180)
			(size 0.3048 0.3048)
			(layers "F.Cu" "F.Mask" "F.Paste")
			(net "GND")
		)
		(pad "J30" smd circle
			(at -1.75514 -9.20242 180)
			(size 0.3048 0.3048)
			(layers "F.Cu" "F.Mask" "F.Paste")
			(net "M_B_DQ29")
		)
		(pad "J37" smd circle
			(at 1.51638 -9.20242 180)
			(size 0.3048 0.3048)
			(layers "F.Cu" "F.Mask" "F.Paste")
			(net "CLK_100M_CPU_HFHPLL_DN")
		)
		(pad "J38" smd circle
			(at 2.21742 -9.20242 180)
			(size 0.3048 0.3048)
			(layers "F.Cu" "F.Mask" "F.Paste")
			(net "TP_CPU_RSVD17")
		)
		(pad "J44" smd circle
			(at 5.48894 -9.20242 180)
			(size 0.3048 0.3048)
			(layers "F.Cu" "F.Mask" "F.Paste")
			(net "Net_1366")
		)
		(pad "J46" smd circle
			(at 6.18998 -9.20242 180)
			(size 0.3048 0.3048)
			(layers "F.Cu" "F.Mask" "F.Paste")
			(net "Net_276")
		)
		(pad "J52" smd circle
			(at 9.4615 -9.20242 180)
			(size 0.3048 0.3048)
			(layers "F.Cu" "F.Mask" "F.Paste")
			(net "SATA2_OBS_P")
		)
		(pad "J54" smd circle
			(at 10.16254 -9.20242 180)
			(size 0.3048 0.3048)
			(layers "F.Cu" "F.Mask" "F.Paste")
			(net "CLK_100M_SATA2_DP")
		)
		(pad "J63" smd circle
			(at 14.5415 -9.10844 180)
			(size 0.3048 0.3048)
			(layers "F.Cu" "F.Mask" "F.Paste")
			(net "GND")
		)
		(pad "J64" smd circle
			(at 15.3035 -9.05764 180)
			(size 0.3048 0.3048)
			(layers "F.Cu" "F.Mask" "F.Paste")
			(net "GND")
		)
		(pad "J66" smd oval
			(at 16.24838 -9.10844 180)
			(size 0.3429 0.254)
			(layers "F.Cu" "F.Mask" "F.Paste")
			(net "GND")
		)
		(pad "K1" smd oval
			(at -16.24838 -8.9027 180)
			(size 0.3429 0.254)
			(layers "F.Cu" "F.Mask" "F.Paste")
			(net "GND")
		)
		(pad "K3" smd circle
			(at -15.3035 -8.9535 180)
			(size 0.3048 0.3048)
			(layers "F.Cu" "F.Mask" "F.Paste")
			(net "M_B_CS_N0")
		)
		(pad "K4" smd circle
			(at -14.5415 -8.9027 180)
			(size 0.3048 0.3048)
			(layers "F.Cu" "F.Mask" "F.Paste")
			(net "M_B_CS_N3")
		)
		(pad "K10" smd circle
			(at -11.68654 -8.82142 180)
			(size 0.3048 0.3048)
			(layers "F.Cu" "F.Mask" "F.Paste")
			(net "PV_VDDR")
		)
		(pad "K17" smd circle
			(at -8.41502 -8.82142 180)
			(size 0.3048 0.3048)
			(layers "F.Cu" "F.Mask" "F.Paste")
			(net "PV_VDDR")
		)
		(pad "K18" smd circle
			(at -7.71398 -8.82142 180)
			(size 0.3048 0.3048)
			(layers "F.Cu" "F.Mask" "F.Paste")
			(net "PV_VDDR")
		)
		(pad "K25" smd circle
			(at -4.44246 -8.82142 180)
			(size 0.3048 0.3048)
			(layers "F.Cu" "F.Mask" "F.Paste")
			(net "PV_VDDR")
		)
		(pad "K26" smd circle
			(at -3.74142 -8.82142 180)
			(size 0.3048 0.3048)
			(layers "F.Cu" "F.Mask" "F.Paste")
			(net "PV_VDDR")
		)
		(pad "K32" smd circle
			(at -0.4699 -8.82142 180)
			(size 0.3048 0.3048)
			(layers "F.Cu" "F.Mask" "F.Paste")
			(net "GND")
		)
		(pad "K34" smd circle
			(at 0.23114 -8.82142 180)
			(size 0.3048 0.3048)
			(layers "F.Cu" "F.Mask" "F.Paste")
			(net "GND")
		)
		(pad "K41" smd circle
			(at 3.50266 -8.82142 180)
			(size 0.3048 0.3048)
			(layers "F.Cu" "F.Mask" "F.Paste")
			(net "P1V0")
		)
		(pad "K42" smd circle
			(at 4.2037 -8.82142 180)
			(size 0.3048 0.3048)
			(layers "F.Cu" "F.Mask" "F.Paste")
			(net "GND")
		)
		(pad "K48" smd circle
			(at 7.47522 -8.82142 180)
			(size 0.3048 0.3048)
			(layers "F.Cu" "F.Mask" "F.Paste")
			(net "CPU_GBE_RX_DN0")
		)
		(pad "K50" smd circle
			(at 8.17626 -8.82142 180)
			(size 0.3048 0.3048)
			(layers "F.Cu" "F.Mask" "F.Paste")
			(net "GND")
		)
		(pad "K62" smd circle
			(at 14.06398 -8.5979 180)
			(size 0.3048 0.3048)
			(layers "F.Cu" "F.Mask" "F.Paste")
			(net "GND")
		)
		(pad "L2" smd circle
			(at -15.80642 -8.14324 180)
			(size 0.3048 0.3048)
			(layers "F.Cu" "F.Mask" "F.Paste")
			(net "M_B_ODT0")
		)
		(pad "L4" smd circle
			(at -14.75232 -8.22198 180)
			(size 0.3048 0.3048)
			(layers "F.Cu" "F.Mask" "F.Paste")
			(net "M_B_ODT3")
		)
		(pad "L5" smd circle
			(at -14.06398 -8.39216 180)
			(size 0.3048 0.3048)
			(layers "F.Cu" "F.Mask" "F.Paste")
			(net "PV_VDDR")
		)
		(pad "L7" smd circle
			(at -13.34516 -8.17626 180)
			(size 0.3048 0.3048)
			(layers "F.Cu" "F.Mask" "F.Paste")
			(net "M_B_CS_N2")
		)
		(pad "L8" smd circle
			(at -12.58316 -8.17626 180)
			(size 0.3048 0.3048)
			(layers "F.Cu" "F.Mask" "F.Paste")
			(net "M_B_RAS#")
		)
		(pad "L13" smd circle
			(at -10.4013 -8.44042 180)
			(size 0.3048 0.3048)
			(layers "F.Cu" "F.Mask" "F.Paste")
			(net "M_B_CK_DN3")
		)
		(pad "L14" smd circle
			(at -9.70026 -8.44042 180)
			(size 0.3048 0.3048)
			(layers "F.Cu" "F.Mask" "F.Paste")
			(net "CLK_100M_CPU_MPLL1_DN")
		)
		(pad "L17" smd circle
			(at -8.41502 -8.05942 180)
			(size 0.3048 0.3048)
			(layers "F.Cu" "F.Mask" "F.Paste")
			(net "M_DRAM_PWROK")
		)
		(pad "L18" smd circle
			(at -7.71398 -8.05942 180)
			(size 0.3048 0.3048)
			(layers "F.Cu" "F.Mask" "F.Paste")
			(net "M_B_MA10")
		)
		(pad "L21" smd circle
			(at -6.42874 -8.44042 180)
			(size 0.3048 0.3048)
			(layers "F.Cu" "F.Mask" "F.Paste")
			(net "PV_VDDR")
		)
		(pad "L22" smd circle
			(at -5.7277 -8.44042 180)
			(size 0.3048 0.3048)
			(layers "F.Cu" "F.Mask" "F.Paste")
			(net "PV_VDDR")
		)
		(pad "L25" smd circle
			(at -4.44246 -8.05942 180)
			(size 0.3048 0.3048)
			(layers "F.Cu" "F.Mask" "F.Paste")
			(net "M_B_CKE2")
		)
		(pad "L26" smd circle
			(at -3.74142 -8.05942 180)
			(size 0.3048 0.3048)
			(layers "F.Cu" "F.Mask" "F.Paste")
			(net "M_B_CKE3")
		)
		(pad "L29" smd circle
			(at -2.45618 -8.44042 180)
			(size 0.3048 0.3048)
			(layers "F.Cu" "F.Mask" "F.Paste")
			(net "M_B_DQS_DN3")
		)
		(pad "L30" smd circle
			(at -1.75514 -8.44042 180)
			(size 0.3048 0.3048)
			(layers "F.Cu" "F.Mask" "F.Paste")
			(net "GND")
		)
		(pad "L32" smd circle
			(at -0.4699 -8.05942 180)
			(size 0.3048 0.3048)
			(layers "F.Cu" "F.Mask" "F.Paste")
			(net "M_B_DQ27")
		)
		(pad "L34" smd circle
			(at 0.23114 -8.05942 180)
			(size 0.3048 0.3048)
			(layers "F.Cu" "F.Mask" "F.Paste")
			(net "GND")
		)
	)
)
